(kicad_pcb
	(version 20260206)
	(generator "pcbnew")
	(generator_version "10.0")
	(general
		(thickness 1.6)
		(legacy_teardrops no)
	)
	(paper "A4")
	(title_block
		(title "15969-1a.1015WZS0858.brd")
		(comment 1 "Tioga Pass / footprints 169-173 of 295")
	)
	(layers
		(0 "F.Cu" signal "TOP")
		(4 "In1.Cu" signal "L2GND")
		(6 "In2.Cu" signal "L3")
		(8 "In3.Cu" signal "L4")
		(10 "In4.Cu" signal "L5GND")
		(2 "B.Cu" signal "BOTTOM")
		(9 "F.Adhes" user "F.Adhesive")
		(11 "B.Adhes" user "B.Adhesive")
		(13 "F.Paste" user "Package Geometry/Pastemask Top")
		(15 "B.Paste" user "Package Geometry/Pastemask Bottom")
		(5 "F.SilkS" user "Ref Des/Silkscreen Top")
		(7 "B.SilkS" user "Ref Des/Silkscreen Bottom")
		(1 "F.Mask" user "Board Geometry/Soldermask Top")
		(3 "B.Mask" user "Board Geometry/Soldermask Bottom")
		(17 "Dwgs.User" user "User.Drawings")
		(19 "Cmts.User" user "User.Comments")
		(21 "Eco1.User" user "User.Eco1")
		(23 "Eco2.User" user "User.Eco2")
		(25 "Edge.Cuts" user "Board Geometry/Outline")
		(27 "Margin" user)
		(31 "F.CrtYd" user "Package Geometry/Place Bound Top")
		(29 "B.CrtYd" user "Package Geometry/Place Bound Bottom")
		(35 "F.Fab" user "Ref Des/Assembly Top")
		(33 "B.Fab" user "Ref Des/Assembly Bottom")
	)
	(footprint ""
		(layer "F.Cu")
		(at 119.1514 -20.193 90)
		(property "Reference" "R120"
			(at 0 0 90)
			(layer "F.SilkS")
			(hide yes)
			(effects
				(font
					(size 1.27 1.27)
				)
			)
		)
		(property "Value" "10KR2F-2-GP"
			(at 0.064008 -3.993896 90)
			(unlocked yes)
			(layer "F.Fab")
			(hide yes)
			(effects
				(font
					(size 1.016 1.016)
					(thickness 0.1524)
				)
			)
		)
		(property "Device Type" "R402H16"
			(at 0.064008 -5.517896 90)
			(unlocked yes)
			(layer "F.Fab")
			(hide yes)
			(effects
				(font
					(size 1.016 1.016)
					(thickness 0.1524)
				)
			)
		)
		(duplicate_pad_numbers_are_jumpers no)
		(fp_line
			(start 0.508 -0.9398)
			(end -0.508 -0.9398)
			(stroke
				(width 0.1524)
				(type default)
			)
			(layer "F.SilkS")
		)
		(fp_line
			(start -0.508 -0.9398)
			(end -0.508 0.9398)
			(stroke
				(width 0.1524)
				(type default)
			)
			(layer "F.SilkS")
		)
		(fp_rect
			(start -0.508 0.9398)
			(end 0.508 -0.9398)
			(stroke
				(width 0)
				(type default)
			)
			(fill no)
			(layer "F.CrtYd")
		)
		(fp_rect
			(start -0.508 0.9398)
			(end 0.508 -0.9398)
			(stroke
				(width 0)
				(type default)
			)
			(fill no)
			(layer "F.Fab")
		)
		(pad "1" smd custom
			(at 0 -0.4445 90)
			(size 0.1397 0.1397)
			(layers "F.Cu" "F.Mask" "F.Paste")
			(net "P3V3_STBY")
			(options
				(clearance outline)
				(anchor circle)
			)
			(primitives
				(gr_poly
					(pts
						(arc
							(start -0.1778 -0.2794)
							(mid -0.249642 -0.249642)
							(end -0.2794 -0.1778)
						)
						(arc
							(start -0.2794 0.1778)
							(mid -0.249642 0.249642)
							(end -0.1778 0.2794)
						)
						(arc
							(start 0.1778 0.2794)
							(mid 0.249642 0.249642)
							(end 0.2794 0.1778)
						)
						(arc
							(start 0.2794 -0.1778)
							(mid 0.249642 -0.249642)
							(end 0.1778 -0.2794)
						)
					)
					(width 0)
					(fill yes)
				)
			)
		)
		(pad "2" smd custom
			(at 0 0.4445 90)
			(size 0.1397 0.1397)
			(layers "F.Cu" "F.Mask" "F.Paste")
			(net "GPIO_B_EXP_A1")
			(options
				(clearance outline)
				(anchor circle)
			)
			(primitives
				(gr_poly
					(pts
						(arc
							(start -0.1778 -0.2794)
							(mid -0.249642 -0.249642)
							(end -0.2794 -0.1778)
						)
						(arc
							(start -0.2794 0.1778)
							(mid -0.249642 0.249642)
							(end -0.1778 0.2794)
						)
						(arc
							(start 0.1778 0.2794)
							(mid 0.249642 0.249642)
							(end 0.2794 0.1778)
						)
						(arc
							(start 0.2794 -0.1778)
							(mid 0.249642 -0.249642)
							(end 0.1778 -0.2794)
						)
					)
					(width 0)
					(fill yes)
				)
			)
		)
	)
	(footprint ""
		(layer "F.Cu")
		(at 118.8466 -27.6098 -90)
		(property "Reference" "CU9"
			(at 0 0 270)
			(layer "F.SilkS")
			(hide yes)
			(effects
				(font
					(size 1.27 1.27)
				)
			)
		)
		(property "Value" "SC1U10V2KX-4-GP"
			(at 1.1811 -2.7051 270)
			(unlocked yes)
			(layer "F.Fab")
			(hide yes)
			(effects
				(font
					(size 1.016 1.016)
					(thickness 0.1524)
				)
			)
		)
		(property "Device Type" "C402H22"
			(at 1.1811 -4.2291 270)
			(unlocked yes)
			(layer "F.Fab")
			(hide yes)
			(effects
				(font
					(size 1.016 1.016)
					(thickness 0.1524)
				)
			)
		)
		(duplicate_pad_numbers_are_jumpers no)
		(fp_rect
			(start -0.4318 0.9525)
			(end 0.4318 -0.9525)
			(stroke
				(width 0)
				(type default)
			)
			(fill no)
			(layer "F.CrtYd")
		)
		(fp_rect
			(start -0.4318 0.9525)
			(end 0.4318 -0.9525)
			(stroke
				(width 0)
				(type default)
			)
			(fill no)
			(layer "F.Fab")
		)
		(pad "1" smd custom
			(at 0 -0.4445 270)
			(size 0.1524 0.1524)
			(layers "F.Cu" "F.Mask" "F.Paste")
			(net "CRFILT")
			(options
				(clearance outline)
				(anchor circle)
			)
			(primitives
				(gr_poly
					(pts
						(arc
							(start 0.3048 -0.2032)
							(mid 0.275042 -0.275042)
							(end 0.2032 -0.3048)
						)
						(arc
							(start -0.2032 -0.3048)
							(mid -0.275042 -0.275042)
							(end -0.3048 -0.2032)
						)
						(arc
							(start -0.3048 0.2032)
							(mid -0.275042 0.275042)
							(end -0.2032 0.3048)
						)
						(arc
							(start 0.2032 0.3048)
							(mid 0.275042 0.275042)
							(end 0.3048 0.2032)
						)
					)
					(width 0)
					(fill yes)
				)
			)
		)
		(pad "2" smd custom
			(at 0 0.4445 270)
			(size 0.1524 0.1524)
			(layers "F.Cu" "F.Mask" "F.Paste")
			(net "GND")
			(options
				(clearance outline)
				(anchor circle)
			)
			(primitives
				(gr_poly
					(pts
						(arc
							(start 0.3048 -0.2032)
							(mid 0.275042 -0.275042)
							(end 0.2032 -0.3048)
						)
						(arc
							(start -0.2032 -0.3048)
							(mid -0.275042 -0.275042)
							(end -0.3048 -0.2032)
						)
						(arc
							(start -0.3048 0.2032)
							(mid -0.275042 0.275042)
							(end -0.2032 0.3048)
						)
						(arc
							(start 0.2032 0.3048)
							(mid 0.275042 0.275042)
							(end 0.3048 0.2032)
						)
					)
					(width 0)
					(fill yes)
				)
			)
		)
	)
	(footprint ""
		(layer "F.Cu")
		(at 124.27458 -28.11653)
		(property "Reference" "U22"
			(at 0 0 0)
			(layer "F.SilkS")
			(hide yes)
			(effects
				(font
					(size 1.27 1.27)
				)
			)
		)
		(property "Value" "USB2513BT-M2-GP"
			(at -6.0198 -6.3246 0)
			(unlocked yes)
			(layer "F.Fab")
			(hide yes)
			(effects
				(font
					(size 1.016 1.016)
					(thickness 0.1524)
				)
			)
		)
		(property "Device Type" "QFN36-G3D8H40"
			(at -6.0198 -7.8486 0)
			(unlocked yes)
			(layer "F.Fab")
			(hide yes)
			(effects
				(font
					(size 1.016 1.016)
					(thickness 0.1524)
				)
			)
		)
		(duplicate_pad_numbers_are_jumpers no)
		(fp_line
			(start -4.5466 -2.0066)
			(end -3.7846 -2.0066)
			(stroke
				(width 0.1524)
				(type default)
			)
			(layer "F.SilkS")
		)
		(fp_line
			(start -4.2926 0.508)
			(end -3.7846 0.508)
			(stroke
				(width 0.1524)
				(type default)
			)
			(layer "F.SilkS")
		)
		(fp_line
			(start -4.0132 -4.0132)
			(end -4.0132 -2.7432)
			(stroke
				(width 0.1524)
				(type default)
			)
			(layer "F.SilkS")
		)
		(fp_line
			(start -4.0132 2.7432)
			(end -4.0132 4.0132)
			(stroke
				(width 0.1524)
				(type default)
			)
			(layer "F.SilkS")
		)
		(fp_line
			(start -4.0132 4.0132)
			(end -2.7432 4.0132)
			(stroke
				(width 0.1524)
				(type default)
			)
			(layer "F.SilkS")
		)
		(fp_line
			(start -2.7432 -4.0132)
			(end -4.0132 -4.0132)
			(stroke
				(width 0.1524)
				(type default)
			)
			(layer "F.SilkS")
		)
		(fp_line
			(start -1.4986 3.7846)
			(end -1.4986 4.5466)
			(stroke
				(width 0.1524)
				(type default)
			)
			(layer "F.SilkS")
		)
		(fp_line
			(start 0 -4.2926)
			(end 0 -3.7846)
			(stroke
				(width 0.1524)
				(type default)
			)
			(layer "F.SilkS")
		)
		(fp_line
			(start 0.9906 3.7846)
			(end 0.9906 4.2926)
			(stroke
				(width 0.1524)
				(type default)
			)
			(layer "F.SilkS")
		)
		(fp_line
			(start 2.7432 4.0132)
			(end 4.0132 4.0132)
			(stroke
				(width 0.1524)
				(type default)
			)
			(layer "F.SilkS")
		)
		(fp_line
			(start 3.7846 -1.4986)
			(end 4.2926 -1.4986)
			(stroke
				(width 0.1524)
				(type default)
			)
			(layer "F.SilkS")
		)
		(fp_line
			(start 3.7846 0.9906)
			(end 4.5466 0.9906)
			(stroke
				(width 0.1524)
				(type default)
			)
			(layer "F.SilkS")
		)
		(fp_line
			(start 4.0132 4.0132)
			(end 4.0132 2.7432)
			(stroke
				(width 0.1524)
				(type default)
			)
			(layer "F.SilkS")
		)
		(fp_poly
			(pts
				(xy 2.7432 -4.0132) (xy 4.0132 -4.0132) (xy 4.0132 -2.7432)
			)
			(stroke
				(width 0)
				(type default)
			)
			(fill yes)
			(layer "F.SilkS")
		)
		(fp_rect
			(start -2.9972 2.9972)
			(end 2.9972 -2.9972)
			(stroke
				(width 0)
				(type default)
			)
			(fill no)
			(layer "F.CrtYd")
		)
		(fp_poly
			(pts
				(xy -4.0132 4.0132) (xy -4.0132 -4.0132) (xy -2.9972 -4.0132) (xy -2.9972 2.9972) (xy 2.9972 2.9972)
				(xy 2.9972 -2.9972) (xy -2.99212 -2.9972) (xy -2.99212 -4.0132) (xy 4.0132 -4.0132) (xy 4.0132 4.0132)
			)
			(stroke
				(width 0)
				(type default)
			)
			(fill no)
			(layer "F.CrtYd")
		)
		(fp_rect
			(start -4.0132 4.0132)
			(end 4.0132 -4.0132)
			(stroke
				(width 0)
				(type default)
			)
			(fill no)
			(layer "F.Fab")
		)
		(pad "1" smd rect
			(at 1.999996 -2.921)
			(size 0.3048 1.1684)
			(layers "F.Cu" "F.Mask" "F.Paste")
			(net "USB_HUB_PCIE_DN0")
		)
		(pad "2" smd rect
			(at 1.500124 -2.8448)
			(size 0.3048 1.3208)
			(layers "F.Cu" "F.Mask" "F.Paste")
			(net "USB_HUB_PCIE_DP0")
		)
		(pad "3" smd rect
			(at 0.999998 -2.8448)
			(size 0.3048 1.3208)
			(layers "F.Cu" "F.Mask" "F.Paste")
			(net "USB_HUB_PCIE_DN1")
		)
		(pad "4" smd rect
			(at 0.500126 -2.8448)
			(size 0.3048 1.3208)
			(layers "F.Cu" "F.Mask" "F.Paste")
			(net "USB_HUB_PCIE_DP1")
		)
		(pad "5" smd rect
			(at 0 -2.8448)
			(size 0.3048 1.3208)
			(layers "F.Cu" "F.Mask" "F.Paste")
			(net "P3V3_USB_HUB")
		)
		(pad "6" smd rect
			(at -0.500126 -2.8448)
			(size 0.3048 1.3208)
			(layers "F.Cu" "F.Mask" "F.Paste")
			(net "USB_DN2")
		)
		(pad "7" smd rect
			(at -0.999998 -2.8448)
			(size 0.3048 1.3208)
			(layers "F.Cu" "F.Mask" "F.Paste")
			(net "USB_DP2")
		)
		(pad "8" smd rect
			(at -1.500124 -2.8448)
			(size 0.3048 1.3208)
			(layers "F.Cu" "F.Mask" "F.Paste")
			(net "TP_USB_DN3")
		)
		(pad "9" smd rect
			(at -1.999996 -2.921)
			(size 0.3048 1.1684)
			(layers "F.Cu" "F.Mask" "F.Paste")
			(net "TP_USB_DP3")
		)
		(pad "10" smd rect
			(at -2.921 -1.999996)
			(size 1.1684 0.3048)
			(layers "F.Cu" "F.Mask" "F.Paste")
			(net "P3V3_USB_HUB")
		)
		(pad "11" smd rect
			(at -2.8448 -1.500124)
			(size 1.3208 0.3048)
			(layers "F.Cu" "F.Mask" "F.Paste")
			(net "GND")
		)
		(pad "12" smd rect
			(at -2.8448 -0.999998)
			(size 1.3208 0.3048)
			(layers "F.Cu" "F.Mask" "F.Paste")
			(net "Net_311")
		)
		(pad "13" smd rect
			(at -2.8448 -0.500126)
			(size 1.3208 0.3048)
			(layers "F.Cu" "F.Mask" "F.Paste")
			(net "TP_USB_OCS_N1")
		)
		(pad "14" smd rect
			(at -2.8448 0)
			(size 1.3208 0.3048)
			(layers "F.Cu" "F.Mask" "F.Paste")
			(net "CRFILT")
		)
		(pad "15" smd rect
			(at -2.8448 0.500126)
			(size 1.3208 0.3048)
			(layers "F.Cu" "F.Mask" "F.Paste")
			(net "P3V3_USB_HUB")
		)
		(pad "16" smd rect
			(at -2.8448 0.999998)
			(size 1.3208 0.3048)
			(layers "F.Cu" "F.Mask" "F.Paste")
			(net "Net_312")
		)
		(pad "17" smd rect
			(at -2.8448 1.500124)
			(size 1.3208 0.3048)
			(layers "F.Cu" "F.Mask" "F.Paste")
			(net "TP_USB_OCS_N2")
		)
		(pad "18" smd rect
			(at -2.921 1.999996)
			(size 1.1684 0.3048)
			(layers "F.Cu" "F.Mask" "F.Paste")
			(net "Net_313")
		)
		(pad "19" smd rect
			(at -1.999996 2.921)
			(size 0.3048 1.1684)
			(layers "F.Cu" "F.Mask" "F.Paste")
			(net "TP_USB_OCS_N3")
		)
		(pad "20" smd rect
			(at -1.500124 2.8448)
			(size 0.3048 1.3208)
			(layers "F.Cu" "F.Mask" "F.Paste")
			(net "Net_310")
		)
		(pad "21" smd rect
			(at -0.999998 2.8448)
			(size 0.3048 1.3208)
			(layers "F.Cu" "F.Mask" "F.Paste")
			(net "TP_USB_OCS_N4")
		)
		(pad "22" smd rect
			(at -0.500126 2.8448)
			(size 0.3048 1.3208)
			(layers "F.Cu" "F.Mask" "F.Paste")
			(net "SMDAT_USB_HUB_R")
		)
		(pad "23" smd rect
			(at 0 2.8448)
			(size 0.3048 1.3208)
			(layers "F.Cu" "F.Mask" "F.Paste")
			(net "P3V3_USB_HUB")
		)
		(pad "24" smd rect
			(at 0.500126 2.8448)
			(size 0.3048 1.3208)
			(layers "F.Cu" "F.Mask" "F.Paste")
			(net "SMCLK_USB_HUB_R")
		)
		(pad "25" smd rect
			(at 0.999998 2.8448)
			(size 0.3048 1.3208)
			(layers "F.Cu" "F.Mask" "F.Paste")
			(net "CFG_SEL1")
		)
		(pad "26" smd rect
			(at 1.500124 2.8448)
			(size 0.3048 1.3208)
			(layers "F.Cu" "F.Mask" "F.Paste")
			(net "USB_RESET_N")
		)
		(pad "27" smd rect
			(at 1.999996 2.921)
			(size 0.3048 1.1684)
			(layers "F.Cu" "F.Mask" "F.Paste")
			(net "VBUS_DET")
		)
		(pad "28" smd rect
			(at 2.921 1.999996)
			(size 1.1684 0.3048)
			(layers "F.Cu" "F.Mask" "F.Paste")
			(net "NON_REM0")
		)
		(pad "29" smd rect
			(at 2.8448 1.500124)
			(size 1.3208 0.3048)
			(layers "F.Cu" "F.Mask" "F.Paste")
			(net "P3V3_USB_HUB")
		)
		(pad "30" smd rect
			(at 2.8448 0.999998)
			(size 1.3208 0.3048)
			(layers "F.Cu" "F.Mask" "F.Paste")
			(net "USB2_P02_DN")
		)
		(pad "31" smd rect
			(at 2.8448 0.500126)
			(size 1.3208 0.3048)
			(layers "F.Cu" "F.Mask" "F.Paste")
			(net "USB2_P02_DP")
		)
		(pad "32" smd rect
			(at 2.8448 0)
			(size 1.3208 0.3048)
			(layers "F.Cu" "F.Mask" "F.Paste")
			(net "USB_HUB_XTAL_OUT")
		)
		(pad "33" smd rect
			(at 2.8448 -0.500126)
			(size 1.3208 0.3048)
			(layers "F.Cu" "F.Mask" "F.Paste")
			(net "USB_HUB_XTAL_IN")
		)
		(pad "34" smd rect
			(at 2.8448 -0.999998)
			(size 1.3208 0.3048)
			(layers "F.Cu" "F.Mask" "F.Paste")
			(net "PLLFILT")
		)
		(pad "35" smd rect
			(at 2.8448 -1.500124)
			(size 1.3208 0.3048)
			(layers "F.Cu" "F.Mask" "F.Paste")
			(net "RBIAS")
		)
		(pad "36" smd rect
			(at 2.921 -1.999996)
			(size 1.1684 0.3048)
			(layers "F.Cu" "F.Mask" "F.Paste")
			(net "P3V3_USB_HUB")
		)
		(pad "37" smd rect
			(at 0 0)
			(size 3.81 3.81)
			(layers "F.Cu" "F.Mask" "F.Paste")
			(net "GND")
		)
	)
	(footprint ""
		(layer "F.Cu")
		(at 128.7018 -22.479 90)
		(property "Reference" "CU13"
			(at 0 0 90)
			(layer "F.SilkS")
			(hide yes)
			(effects
				(font
					(size 1.27 1.27)
				)
			)
		)
		(property "Value" "SCD1U16V2KX-3GP"
			(at 1.1811 -2.7051 90)
			(unlocked yes)
			(layer "F.Fab")
			(hide yes)
			(effects
				(font
					(size 1.016 1.016)
					(thickness 0.1524)
				)
			)
		)
		(property "Device Type" "C402H22"
			(at 1.1811 -4.2291 90)
			(unlocked yes)
			(layer "F.Fab")
			(hide yes)
			(effects
				(font
					(size 1.016 1.016)
					(thickness 0.1524)
				)
			)
		)
		(duplicate_pad_numbers_are_jumpers no)
		(fp_rect
			(start -0.4318 0.9525)
			(end 0.4318 -0.9525)
			(stroke
				(width 0)
				(type default)
			)
			(fill no)
			(layer "F.CrtYd")
		)
		(fp_rect
			(start -0.4318 0.9525)
			(end 0.4318 -0.9525)
			(stroke
				(width 0)
				(type default)
			)
			(fill no)
			(layer "F.Fab")
		)
		(pad "1" smd custom
			(at 0 -0.4445 90)
			(size 0.1524 0.1524)
			(layers "F.Cu" "F.Mask" "F.Paste")
			(net "VBUS_DET")
			(options
				(clearance outline)
				(anchor circle)
			)
			(primitives
				(gr_poly
					(pts
						(arc
							(start 0.3048 -0.2032)
							(mid 0.275042 -0.275042)
							(end 0.2032 -0.3048)
						)
						(arc
							(start -0.2032 -0.3048)
							(mid -0.275042 -0.275042)
							(end -0.3048 -0.2032)
						)
						(arc
							(start -0.3048 0.2032)
							(mid -0.275042 0.275042)
							(end -0.2032 0.3048)
						)
						(arc
							(start 0.2032 0.3048)
							(mid 0.275042 0.275042)
							(end 0.3048 0.2032)
						)
					)
					(width 0)
					(fill yes)
				)
			)
		)
		(pad "2" smd custom
			(at 0 0.4445 90)
			(size 0.1524 0.1524)
			(layers "F.Cu" "F.Mask" "F.Paste")
			(net "GND")
			(options
				(clearance outline)
				(anchor circle)
			)
			(primitives
				(gr_poly
					(pts
						(arc
							(start 0.3048 -0.2032)
							(mid 0.275042 -0.275042)
							(end 0.2032 -0.3048)
						)
						(arc
							(start -0.2032 -0.3048)
							(mid -0.275042 -0.275042)
							(end -0.3048 -0.2032)
						)
						(arc
							(start -0.3048 0.2032)
							(mid -0.275042 0.275042)
							(end -0.2032 0.3048)
						)
						(arc
							(start 0.2032 0.3048)
							(mid 0.275042 0.275042)
							(end 0.3048 0.2032)
						)
					)
					(width 0)
					(fill yes)
				)
			)
		)
	)
	(footprint ""
		(layer "F.Cu")
		(at 119.634 -11.2522 90)
		(property "Reference" "R171"
			(at 0 0 90)
			(layer "F.SilkS")
			(hide yes)
			(effects
				(font
					(size 1.27 1.27)
				)
			)
		)
		(property "Value" "4K7R2F-GP"
			(at 0.064008 -3.993896 90)
			(unlocked yes)
			(layer "F.Fab")
			(hide yes)
			(effects
				(font
					(size 1.016 1.016)
					(thickness 0.1524)
				)
			)
		)
		(property "Device Type" "R402H16"
			(at 0.064008 -5.517896 90)
			(unlocked yes)
			(layer "F.Fab")
			(hide yes)
			(effects
				(font
					(size 1.016 1.016)
					(thickness 0.1524)
				)
			)
		)
		(duplicate_pad_numbers_are_jumpers no)
		(fp_line
			(start 0.508 -0.9398)
			(end -0.508 -0.9398)
			(stroke
				(width 0.1524)
				(type default)
			)
			(layer "F.SilkS")
		)
		(fp_line
			(start -0.508 -0.9398)
			(end -0.508 0.9398)
			(stroke
				(width 0.1524)
				(type default)
			)
			(layer "F.SilkS")
		)
		(fp_rect
			(start -0.508 0.9398)
			(end 0.508 -0.9398)
			(stroke
				(width 0)
				(type default)
			)
			(fill no)
			(layer "F.CrtYd")
		)
		(fp_rect
			(start -0.508 0.9398)
			(end 0.508 -0.9398)
			(stroke
				(width 0)
				(type default)
			)
			(fill no)
			(layer "F.Fab")
		)
		(pad "1" smd custom
			(at 0 -0.4445 90)
			(size 0.1397 0.1397)
			(layers "F.Cu" "F.Mask" "F.Paste")
			(net "P3V3_STBY")
			(options
				(clearance outline)
				(anchor circle)
			)
			(primitives
				(gr_poly
					(pts
						(arc
							(start -0.1778 -0.2794)
							(mid -0.249642 -0.249642)
							(end -0.2794 -0.1778)
						)
						(arc
							(start -0.2794 0.1778)
							(mid -0.249642 0.249642)
							(end -0.1778 0.2794)
						)
						(arc
							(start 0.1778 0.2794)
							(mid 0.249642 0.249642)
							(end 0.2794 0.1778)
						)
						(arc
							(start 0.2794 -0.1778)
							(mid 0.249642 -0.249642)
							(end 0.1778 -0.2794)
						)
					)
					(width 0)
					(fill yes)
				)
			)
		)
		(pad "2" smd custom
			(at 0 0.4445 90)
			(size 0.1397 0.1397)
			(layers "F.Cu" "F.Mask" "F.Paste")
			(net "PCIE_SLOT3_PRSNT2_4_N")
			(options
				(clearance outline)
				(anchor circle)
			)
			(primitives
				(gr_poly
					(pts
						(arc
							(start -0.1778 -0.2794)
							(mid -0.249642 -0.249642)
							(end -0.2794 -0.1778)
						)
						(arc
							(start -0.2794 0.1778)
							(mid -0.249642 0.249642)
							(end -0.1778 0.2794)
						)
						(arc
							(start 0.1778 0.2794)
							(mid 0.249642 0.249642)
							(end 0.2794 0.1778)
						)
						(arc
							(start 0.2794 -0.1778)
							(mid 0.249642 -0.249642)
							(end 0.1778 -0.2794)
						)
					)
					(width 0)
					(fill yes)
				)
			)
		)
	)
)
